FILE_TYPE = CONNECTIVITY;
{Allegro Design Entry HDL 17.2-2016 S081 (4005846) 1/11/2022}
"PAGE_NUMBER" = 174;
0"NC";
1"GND\g";
2"GND\g";
3"GND\g";
4"GND\g";
5"GND\g";
6"SW_PVDDCR_SOC_P0_SW3_RC";
7"PVDDCR_SOC_P0_VOS3";
8"NC_PVDDCR_SOC_P0_GL2_3";
9"IND_SOC_P0_CPL0";
10"SW_PVDDCR_SOC_P0_SW3";
11"PVDDCR_SOC_P0\g";
12"PVDDCR_CPU0_P0_VCCS";
13"SW_PVDDCR_SOC_P0_PH3";
14"GND\g";
15"PVDDCR_SOC_P0_LSET3";
16"NC_PVDDCR_SOC_P0_DNC3";
17"PVDDCR_SOC_P0_TEMP1";
18"PVDDCR_SOC_P0_PWM3";
19"GND\g";
20"NC_PVDDCR_SOC_P0_GL1_3";
21"PVDDCR_SOC_P0_VCC3";
22"PVDDCR_CPU0_P0_PVCC\g";
23"PVDDCR_SOC_P0_IMON3";
24"SW_P12V_STBY_PVDDCR_SOC_P0_FLT\g";
25"SW_PVDDCR_SOC_P0_BOOT3";
26"GND\g";
27"IND_SOC_P0_CPL3";
28"GND\g";
29"SW_PVDDCR_SOC_P0_BOOT3_RC";
%"UNIVERSAL_GND"
"1","(-5250,3425)","0","pure_quanta_power","I16";
;
CDS_LIB"pure_quanta_power"
HDL_POWER"GND";
"A"19;
%"Q_RES"
"1","(-4050,3200)","0","pure_quanta","I17";
;
LOCATION"PR367"
$SEC"1"
CDS_SEC"1"
WATTAGE"1/16W"
MATERIAL"CHIP"
TOLERANCE"5%"
VALUE"0"
PART_NUMBER"CS00002JB38"
PACK_TYPE"0402LF"
CDS_LIB"pure_quanta";
"B"
$PN"2"11;
"A"
$PN"1"7;
%"Q_RES"
"1","(-4525,4500)","0","pure_quanta","I18";
;
LOCATION"PR366"
$SEC"1"
CDS_SEC"1"
PACK_TYPE"0402LF"
TOLERANCE"1%"
MATERIAL"CHIP"
WATTAGE"1/16W"
VALUE"4.7"
PART_NUMBER"CS-4702FB19"
CDS_LIB"pure_quanta";
"B"
$PN"2"29;
"A"
$PN"1"25;
%"UNIVERSAL_GND"
"1","(-7650,3600)","0","pure_quanta_power","I2";
;
CDS_LIB"pure_quanta_power"
HDL_POWER"GND";
"A"1;
%"Q_CAP"
"1","(-4625,5025)","0","pure_quanta","I20";
;
LOCATION"PC609_3"
$SEC"1"
CDS_SEC"1"
MATERIAL"X6S"
TOLERANCE"10%"
VALUE"1UF"
PART_NUMBER"CH5104KEB02"
VOLTAGE"25V"
PACK_TYPE"C0402"
CDS_LIB"pure_quanta";
"B"
$PN"2"26;
"A"
$PN"1"24;
%"Q_CAP"
"1","(-4300,5025)","0","pure_quanta","I21";
;
LOCATION"PC610_3"
$SEC"1"
CDS_SEC"1"
MATERIAL"X6S"
TOLERANCE"10%"
VALUE"10UF"
PART_NUMBER"CH6104KEA00"
VOLTAGE"25V"
PACK_TYPE"C0805"
CDS_LIB"pure_quanta";
"B"
$PN"2"26;
"A"
$PN"1"24;
%"Q_CAP"
"1","(-3975,5025)","0","pure_quanta","I22";
;
LOCATION"PC611_3"
$SEC"1"
CDS_SEC"1"
MATERIAL"X6S"
TOLERANCE"10%"
VALUE"10UF"
PART_NUMBER"CH6104KEA00"
VOLTAGE"25V"
PACK_TYPE"C0805"
CDS_LIB"pure_quanta";
"B"
$PN"2"26;
"A"
$PN"1"24;
%"UNIVERSAL_GND"
"1","(-3325,4700)","0","pure_quanta_power","I23";
;
CDS_LIB"pure_quanta_power"
HDL_POWER"GND";
"A"26;
%"Q_CAP"
"1","(-1750,3975)","0","pure_quanta","I25";
;
LOCATION"PC614_3"
$SEC"1"
CDS_SEC"1"
MATERIAL"X6S"
TOLERANCE"20%"
VALUE"22UF"
PART_NUMBER"TMP_QCH622KMEA01"
VOLTAGE"4V"
PACK_TYPE"0805"
CDS_LIB"pure_quanta";
"B"
$PN"2"28;
"A"
$PN"1"11;
%"Q_CAP"
"1","(-3675,5025)","0","pure_quanta","I26";
;
LOCATION"PC613_3"
$SEC"1"
CDS_SEC"1"
MATERIAL"X6S"
TOLERANCE"10%"
VALUE"10UF"
PART_NUMBER"CH6104KEA00"
VOLTAGE"25V"
PACK_TYPE"C0805"
CDS_LIB"pure_quanta";
"B"
$PN"2"26;
"A"
$PN"1"24;
%"VCC_CORE"
"1","(-3325,5325)","0","pure_quanta_power","I27";
;
HDL_POWER"SW_P12V_STBY_PVDDCR_SOC_P0_FLT"
CDS_LIB"pure_quanta_power";
"A"24;
%"UNIVERSAL_GND"
"1","(-1325,3625)","0","pure_quanta_power","I28";
;
CDS_LIB"pure_quanta_power"
HDL_POWER"GND";
"A"28;
%"Q_CAP"
"1","(-1325,3975)","0","pure_quanta","I29";
;
LOCATION"PC615_3"
$SEC"1"
CDS_SEC"1"
MATERIAL"X6S"
TOLERANCE"20%"
VALUE"22UF"
PART_NUMBER"TMP_QCH622KMEA01"
VOLTAGE"4V"
PACK_TYPE"0805"
CDS_LIB"pure_quanta";
"B"
$PN"2"28;
"A"
$PN"1"11;
%"UNIVERSAL_GND"
"1","(-7325,3675)","0","pure_quanta_power","I3";
;
CDS_LIB"pure_quanta_power"
HDL_POWER"GND";
"A"2;
%"VCC_CORE"
"1","(-1325,4300)","0","pure_quanta_power","I30";
;
HDL_POWER"PVDDCR_SOC_P0"
CDS_LIB"pure_quanta_power";
"A"11;
%"Q_INDUCTOR4P_14"
"1","(-2925,4025)","0","pure_quanta","I31";
;
LOCATION"PL66"
$SEC"1"
CDS_SEC"1"
PART_TYPE"SMLF"
VALUE"150NH"
PART_NUMBER"CV+15^0TZ04"
MATERIAL"IND"
CDS_LIB"pure_quanta"
NEEDS_NO_SIZE"TRUE";
"1"
$PN"1"10;
"4"
$PN"4"11;
"3"
$PN"3"27;
"2"
$PN"2"9;
%"Q_CAP"
"1","(-3700,4375)","0","pure_quanta","I32";
;
LOCATION"PC612"
$SEC"1"
CDS_SEC"1"
MATERIAL"X7R"
TOLERANCE"10%"
VALUE"0.22UF"
PART_NUMBER"CH4223K1B00"
VOLTAGE"16V"
PACK_TYPE"0402"
CDS_LIB"pure_quanta";
"B"
$PN"2"13;
"A"
$PN"1"29;
%"Q_CAP"
"1","(-5025,5025)","0","pure_quanta","I37";
;
LOCATION"PC608_3"
$SEC"1"
CDS_SEC"1"
MATERIAL"X7R"
TOLERANCE"10%"
VALUE"0.1UF"
PART_NUMBER"CH4104K1B00"
VOLTAGE"25V"
PACK_TYPE"0402"
CDS_LIB"pure_quanta";
"B"
$PN"2"26;
"A"
$PN"1"24;
%"Q_CAP"
"1","(-7325,4500)","0","pure_quanta","I38";
;
LOCATION"PC606"
$SEC"1"
CDS_SEC"1"
MATERIAL"X6S"
TOLERANCE"10%"
VALUE"2.2UF"
PART_NUMBER"CH5222KEB01"
VOLTAGE"10V"
PACK_TYPE"C0402"
CDS_LIB"pure_quanta";
"B"
$PN"2"3;
"A"
$PN"1"21;
%"UNIVERSAL_GND"
"1","(-7325,4300)","0","pure_quanta_power","I39";
;
CDS_LIB"pure_quanta_power"
HDL_POWER"GND";
"A"3;
%"UNIVERSAL_GND"
"1","(-6975,4725)","0","pure_quanta_power","I40";
;
CDS_LIB"pure_quanta_power"
HDL_POWER"GND";
"A"4;
%"Q_RES"
"2","(-7325,4975)","0","pure_quanta","I41";
;
LOCATION"PR364"
$SEC"1"
CDS_SEC"1"
WATTAGE"1/16W"
MATERIAL"CHIP"
TOLERANCE"1%"
VALUE"2.2"
PART_NUMBER"CS-2202FB00"
PACK_TYPE"0402LF"
CDS_LIB"pure_quanta";
"A"
$PN"1"22;
"B"
$PN"2"21;
%"Q_CAP"
"1","(-6975,4975)","0","pure_quanta","I42";
;
LOCATION"PC607_SOP0_3"
$SEC"1"
CDS_SEC"1"
MATERIAL"X6S"
TOLERANCE"10%"
VALUE"2.2UF"
PART_NUMBER"CH5222KEB01"
VOLTAGE"10V"
PACK_TYPE"C0402"
CDS_LIB"pure_quanta";
"B"
$PN"2"4;
"A"
$PN"1"22;
%"ISL99390FRZTR5935"
"1","(-5825,4150)","0","pure_quanta","I44";
;
LOCATION"PU51"
$SEC"1"
CDS_SEC"1"
PART_TYPE"SMLF"
MATERIAL"IC"
VALUE"ISL99390FRZ-TR5935"
PART_NUMBER"AL099390004"
CDS_LIB"pure_quanta"
NEEDS_NO_SIZE"TRUE"
CDS_LMAN_SYM_OUTLINE"-300,700,250,-650";
"PGND2"
$PN"7_9-20_24"19;
"GL2"
$PN"41"8;
"GL1"
$PN"6"20;
"DNC"
$PN"31"16;
"EN"
$PN"35"21;
"PGND3"
$PN"40"19;
"VOS"
$PN"1"7;
"VIN2"
$PN"30"24;
"PGND1"
$PN"5"19;
"SW"
$PN"10_19"10;
"LSET"
$PN"37"15;
"IOUT"
$PN"38"23;
"TOUT_FLT"
$PN"36"17;
"PVCC"
$PN"4"22;
"PHASE"
$PN"32"13;
"VIN1"
$PN"25_29"24;
"BOOT"
$PN"33"25;
"AGND"
$PN"2"19;
"VCC"
$PN"3"21;
"REFIN"
$PN"39"12;
"PWM"
$PN"34"18;
%"Q_CAP"
"1","(-4475,3975)","0","pure_quanta","I46";
;
LOCATION"PC188"
$SEC"1"
CDS_SEC"1"
TOLERANCE"10%"
VALUE"560PF"
VOLTAGE"50V"
MATERIAL"EMPTY"
PACK_TYPE"C0402"
PART_NUMBER"CH1566K1B09"
CDS_LIB"pure_quanta";
"B"
$PN"2"6;
"A"
$PN"1"10;
%"Q_RES"
"2","(-4475,3500)","0","pure_quanta","I47";
;
LOCATION"PR505"
$SEC"1"
CDS_SEC"1"
WATTAGE"1/8W"
MATERIAL"EMPTY"
TOLERANCE"1%"
VALUE"1.5"
PART_NUMBER"CS-1504FB00"
PACK_TYPE"0402LF"
CDS_LIB"pure_quanta";
"A"
$PN"1"6;
"B"
$PN"2"5;
%"UNIVERSAL_GND"
"1","(-4475,3275)","0","pure_quanta_power","I48";
;
CDS_LIB"pure_quanta_power"
HDL_POWER"GND";
"A"5;
%"VCC_CORE"
"1","(-7325,5375)","0","pure_quanta_power","I49";
;
HDL_POWER"PVDDCR_CPU0_P0_PVCC"
CDS_LIB"pure_quanta_power";
"A"22;
%"Q_CAP"
"1","(-3325,5025)","0","pure_quanta","I50";
;
LOCATION"PC612_3"
$SEC"1"
CDS_SEC"1"
MATERIAL"X6S"
TOLERANCE"10%"
VALUE"10UF"
PART_NUMBER"CH6104KEA00"
VOLTAGE"25V"
PACK_TYPE"C0805"
CDS_LIB"pure_quanta";
"B"
$PN"2"26;
"A"
$PN"1"24;
%"Q_INDUCTOR"
"1","(-3875,3925)","0","pure_quanta","I51";
;
LOCATION"PL62"
$SEC"1"
CDS_SEC"1"
MATERIAL"IND"
VALUE"0.22UH/33A"
PART_NUMBER"CV+22Y0EZ00"
PACK_TYPE"SMLF"
NEEDS_NO_SIZE"TRUE"
CDS_LIB"pure_quanta";
"1"
$PN"1"14;
"2"
$PN"2"9;
%"UNIVERSAL_GND"
"1","(-4075,3800)","0","pure_quanta_power","I52";
;
CDS_LIB"pure_quanta_power"
HDL_POWER"GND";
"A"14;
%"Q_CAP"
"1","(-7650,3875)","0","pure_quanta","I6";
;
LOCATION"PC605_9"
$SEC"1"
CDS_SEC"1"
MATERIAL"X7R"
TOLERANCE"10%"
VALUE"0.1UF"
PART_NUMBER"CH4104K1B00"
VOLTAGE"25V"
PACK_TYPE"0402"
CDS_LIB"pure_quanta";
"B"
$PN"2"1;
"A"
$PN"1"12;
%"Q_RES"
"1","(-7000,3850)","0","pure_quanta","I7";
;
LOCATION"PR365"
$SEC"1"
CDS_SEC"1"
WATTAGE"1/16W"
MATERIAL"EMPTY"
TOLERANCE"1%"
VALUE"8.87K"
PART_NUMBER"CS28872FB01"
PACK_TYPE"0402LF"
CDS_LIB"pure_quanta";
"B"
$PN"2"15;
"A"
$PN"1"2;
END.
